#ISCELL
  pure_quanta quanta_title_block_c *
  *
#CELL
  pure_quanta q_cap *
  page74_i1
#CELL
  pure_quanta q_cap *
  page74_i10
#CELL
  pure_quanta q_cap *
  page74_i100
#ISCELL
  logical_power universal_gnd *
  page74_i101
#CELL
  pure_quanta q_cap *
  page74_i102
#CELL
  pure_quanta q_cap *
  page74_i103
#ISCELL
  logical_power universal_power *
  page74_i104
#CELL
  pure_quanta q_cap *
  page74_i105
#CELL
  pure_quanta q_cap *
  page74_i106
#CELL
  pure_quanta q_cap *
  page74_i107
#CELL
  pure_quanta q_cap *
  page74_i108
#CELL
  pure_quanta q_cap *
  page74_i109
#CELL
  pure_quanta q_cap *
  page74_i11
#CELL
  pure_quanta q_cap *
  page74_i110
#CELL
  pure_quanta q_cap *
  page74_i111
#CELL
  pure_quanta q_cap *
  page74_i112
#CELL
  pure_quanta q_cap *
  page74_i113
#CELL
  pure_quanta q_cap *
  page74_i114
#CELL
  pure_quanta q_cap *
  page74_i115
#CELL
  pure_quanta q_cap *
  page74_i116
#CELL
  pure_quanta q_cap *
  page74_i117
#CELL
  pure_quanta q_cap *
  page74_i118
#CELL
  pure_quanta q_cap *
  page74_i119
#ISCELL
  logical_power universal_power *
  page74_i12
#CELL
  pure_quanta q_cap *
  page74_i120
#CELL
  pure_quanta q_cap *
  page74_i121
#CELL
  pure_quanta q_cap *
  page74_i122
#CELL
  pure_quanta q_cap *
  page74_i123
#CELL
  pure_quanta q_cap *
  page74_i124
#CELL
  pure_quanta q_cap *
  page74_i125
#ISCELL
  logical_power universal_power *
  page74_i126
#CELL
  pure_quanta q_cap *
  page74_i127
#CELL
  pure_quanta q_cap *
  page74_i128
#ISCELL
  logical_power universal_gnd *
  page74_i129
#CELL
  pure_quanta q_cap *
  page74_i13
#CELL
  pure_quanta q_cap *
  page74_i130
#CELL
  pure_quanta q_cap *
  page74_i131
#CELL
  pure_quanta q_cap *
  page74_i132
#CELL
  pure_quanta q_cap *
  page74_i133
#CELL
  pure_quanta q_cap *
  page74_i134
#CELL
  pure_quanta q_cap *
  page74_i135
#ISCELL
  logical_power universal_gnd *
  page74_i136
#CELL
  pure_quanta q_cap *
  page74_i137
#ISCELL
  logical_power universal_gnd *
  page74_i138
#CELL
  pure_quanta q_cap *
  page74_i139
#ISCELL
  logical_power universal_power *
  page74_i14
#ISCELL
  logical_power universal_gnd *
  page74_i140
#CELL
  pure_quanta q_cap *
  page74_i141
#CELL
  pure_quanta q_cap *
  page74_i142
#CELL
  pure_quanta q_cap *
  page74_i15
#ISCELL
  logical_power universal_power *
  page74_i16
#CELL
  pure_quanta q_cap *
  page74_i17
#CELL
  pure_quanta q_cap *
  page74_i18
#CELL
  pure_quanta q_cap *
  page74_i19
#ISCELL
  logical_power universal_power *
  page74_i2
#CELL
  pure_quanta q_cap *
  page74_i20
#CELL
  pure_quanta q_cap *
  page74_i21
#CELL
  pure_quanta q_cap *
  page74_i22
#CELL
  pure_quanta q_cap *
  page74_i23
#ISCELL
  logical_power universal_power *
  page74_i24
#CELL
  pure_quanta q_cap *
  page74_i25
#ISCELL
  logical_power universal_power *
  page74_i26
#CELL
  pure_quanta q_cap *
  page74_i27
#CELL
  pure_quanta q_cap *
  page74_i28
#CELL
  pure_quanta q_cap *
  page74_i29
#CELL
  pure_quanta q_cap *
  page74_i3
#CELL
  pure_quanta q_cap *
  page74_i30
#CELL
  pure_quanta q_cap *
  page74_i31
#CELL
  pure_quanta q_cap *
  page74_i32
#CELL
  pure_quanta q_cap *
  page74_i33
#CELL
  pure_quanta q_cap *
  page74_i34
#CELL
  pure_quanta q_cap *
  page74_i35
#CELL
  pure_quanta q_cap *
  page74_i36
#CELL
  pure_quanta q_cap *
  page74_i37
#CELL
  pure_quanta q_cap *
  page74_i38
#ISCELL
  logical_power universal_power *
  page74_i39
#CELL
  pure_quanta q_cap *
  page74_i4
#CELL
  pure_quanta q_cap *
  page74_i40
#CELL
  pure_quanta q_cap *
  page74_i41
#CELL
  pure_quanta q_cap *
  page74_i42
#CELL
  pure_quanta q_cap *
  page74_i43
#CELL
  pure_quanta q_cap *
  page74_i44
#CELL
  pure_quanta q_cap *
  page74_i45
#CELL
  pure_quanta q_cap *
  page74_i46
#CELL
  pure_quanta q_cap *
  page74_i47
#CELL
  pure_quanta q_cap *
  page74_i48
#CELL
  pure_quanta q_cap *
  page74_i49
#CELL
  pure_quanta q_cap *
  page74_i5
#CELL
  pure_quanta q_cap *
  page74_i50
#CELL
  pure_quanta q_cap *
  page74_i51
#CELL
  pure_quanta q_cap *
  page74_i52
#CELL
  pure_quanta q_cap *
  page74_i53
#CELL
  pure_quanta q_cap *
  page74_i54
#CELL
  pure_quanta q_cap *
  page74_i55
#CELL
  pure_quanta q_cap *
  page74_i56
#CELL
  pure_quanta q_cap *
  page74_i57
#CELL
  pure_quanta q_cap *
  page74_i58
#CELL
  pure_quanta q_cap *
  page74_i59
#ISCELL
  logical_power universal_gnd *
  page74_i6
#CELL
  pure_quanta q_cap *
  page74_i60
#CELL
  pure_quanta q_cap *
  page74_i61
#CELL
  pure_quanta q_cap *
  page74_i62
#ISCELL
  logical_power universal_power *
  page74_i63
#CELL
  pure_quanta q_cap *
  page74_i64
#CELL
  pure_quanta q_cap *
  page74_i65
#ISCELL
  logical_power universal_gnd *
  page74_i66
#ISCELL
  logical_power universal_gnd *
  page74_i67
#CELL
  pure_quanta q_cap *
  page74_i68
#ISCELL
  logical_power universal_gnd *
  page74_i69
#CELL
  pure_quanta q_cap *
  page74_i7
#CELL
  pure_quanta q_cap *
  page74_i70
#CELL
  pure_quanta q_cap *
  page74_i71
#CELL
  pure_quanta q_cap *
  page74_i72
#ISCELL
  logical_power universal_gnd *
  page74_i73
#CELL
  pure_quanta q_cap *
  page74_i74
#CELL
  pure_quanta q_cap *
  page74_i75
#ISCELL
  logical_power universal_gnd *
  page74_i76
#CELL
  pure_quanta q_cap *
  page74_i77
#CELL
  pure_quanta q_cap *
  page74_i78
#ISCELL
  logical_power universal_power *
  page74_i79
#CELL
  pure_quanta q_cap *
  page74_i8
#CELL
  pure_quanta q_cap *
  page74_i80
#CELL
  pure_quanta q_cap *
  page74_i81
#ISCELL
  logical_power universal_gnd *
  page74_i82
#CELL
  pure_quanta q_cap *
  page74_i83
#ISCELL
  logical_power universal_gnd *
  page74_i84
#CELL
  pure_quanta q_cap *
  page74_i85
#CELL
  pure_quanta q_cap *
  page74_i86
#CELL
  pure_quanta q_cap *
  page74_i87
#ISCELL
  logical_power universal_gnd *
  page74_i88
#CELL
  pure_quanta q_cap *
  page74_i89
#CELL
  pure_quanta q_cap *
  page74_i9
#CELL
  pure_quanta q_cap *
  page74_i90
#ISCELL
  logical_power universal_power *
  page74_i91
#CELL
  pure_quanta q_cap *
  page74_i92
#CELL
  pure_quanta q_cap *
  page74_i93
#ISCELL
  logical_power universal_power *
  page74_i94
#CELL
  pure_quanta q_cap *
  page74_i95
#CELL
  pure_quanta q_cap *
  page74_i96
#CELL
  pure_quanta q_cap *
  page74_i97
#CELL
  pure_quanta q_cap *
  page74_i98
#ISCELL
  logical_power universal_power *
  page74_i99
